# T6G (Grand Teton) — schematic netlist excerpt (pin names and nets, part order shuffled) for the footprints in the layout excerpt that follows; sources: Cadence DE-HDL packaged netlist, KiCad conversion of 04192023_DAF0TMB3IC0_F0TG_MB_C_brd_V02_OCP.brd

R335  Q_RES  10K 1% CHIP  pkg 0402LF  page 188 : A = P12V_AUX ; B = VR_P5V_EN_D_R
C6614  Q_CAP_DIFFBUS  DIFF BUS_0.22UF 6.3V 20% X6S  pkg C0201  page 308 : \1\ = P5E_CPU0_P3_TX_BUF_C_DN<8> ; \2\ = P5E_CPU0_P3_TX_BUF_DN<8>
C119  Q_CAP  10UF 6.3V 20% X6S  pkg C0402  page 323 : A = P1V8_CPU1_RT0_1A ; B = GND

(kicad_pcb
	(version 20260206)
	(generator "pcbnew")
	(generator_version "10.0")
	(general
		(thickness 1.6)
		(legacy_teardrops no)
	)
	(paper "A4")
	(title_block
		(title "04192023_DAF0TMB3IC0_F0TG_MB_C_brd_V02_OCP.brd")
		(comment 1 "Grand Teton / footprints 6902-6904 of 8354")
	)
	(layers
		(0 "F.Cu" signal "TOP")
		(4 "In1.Cu" signal "GND")
		(6 "In2.Cu" signal "IN1")
		(8 "In3.Cu" signal "GND1")
		(10 "In4.Cu" signal "IN2")
		(12 "In5.Cu" signal "GND2")
		(14 "In6.Cu" signal "IN3")
		(16 "In7.Cu" signal "GND3")
		(18 "In8.Cu" signal "VCC")
		(20 "In9.Cu" signal "VCC1")
		(22 "In10.Cu" signal "GND4")
		(24 "In11.Cu" signal "IN4")
		(26 "In12.Cu" signal "GND5")
		(28 "In13.Cu" signal "IN5")
		(30 "In14.Cu" signal "GND6")
		(32 "In15.Cu" signal "IN6")
		(34 "In16.Cu" signal "GND7")
		(2 "B.Cu" signal "BOTTOM")
		(9 "F.Adhes" user "F.Adhesive")
		(11 "B.Adhes" user "B.Adhesive")
		(13 "F.Paste" user "Package Geometry/Pastemask Top")
		(15 "B.Paste" user "Package Geometry/Pastemask Bottom")
		(5 "F.SilkS" user "Ref Des/Silkscreen Top")
		(7 "B.SilkS" user "Ref Des/Silkscreen Bottom")
		(1 "F.Mask" user "Board Geometry/Soldermask Top")
		(3 "B.Mask" user "Board Geometry/Soldermask Bottom")
		(17 "Dwgs.User" user "User.Drawings")
		(19 "Cmts.User" user "User.Comments")
		(21 "Eco1.User" user "User.Eco1")
		(23 "Eco2.User" user "User.Eco2")
		(25 "Edge.Cuts" user "Board Geometry/Outline")
		(27 "Margin" user)
		(31 "F.CrtYd" user "Package Geometry/Place Bound Top")
		(29 "B.CrtYd" user "Package Geometry/Place Bound Bottom")
		(35 "F.Fab" user "Ref Des/Assembly Top")
		(33 "B.Fab" user "Ref Des/Assembly Bottom")
	)
	(footprint ""
		(layer "B.Cu")
		(at 399.796 -144.018 -90)
		(property "Reference" "R335"
			(at 0 0 90)
			(layer "B.SilkS")
			(hide yes)
			(effects
				(font
					(size 1.27 1.27)
				)
				(justify mirror)
			)
		)
		(property "Value" ""
			(at 0 0 90)
			(layer "B.Fab")
			(effects
				(font
					(size 1.27 1.27)
				)
				(justify mirror)
			)
		)
		(duplicate_pad_numbers_are_jumpers no)
		(fp_line
			(start -0.7874 0.4064)
			(end 0.7874 0.4064)
			(stroke
				(width 0.1524)
				(type default)
			)
			(layer "B.SilkS")
		)
		(fp_line
			(start 0.7874 0.4064)
			(end 0.7874 -0.4064)
			(stroke
				(width 0.1524)
				(type default)
			)
			(layer "B.SilkS")
		)
		(fp_line
			(start -0.7874 -0.4064)
			(end -0.7874 0.4064)
			(stroke
				(width 0.1524)
				(type default)
			)
			(layer "B.SilkS")
		)
		(fp_line
			(start 0.7874 -0.4064)
			(end -0.7874 -0.4064)
			(stroke
				(width 0.1524)
				(type default)
			)
			(layer "B.SilkS")
		)
		(fp_line
			(start -0.67945 0.3048)
			(end -0.120396 0.3048)
			(stroke
				(width 0.1)
				(type default)
			)
			(layer "B.Fab")
		)
		(fp_line
			(start -0.120396 0.3048)
			(end -0.120396 0.2794)
			(stroke
				(width 0.1)
				(type default)
			)
			(layer "B.Fab")
		)
		(fp_line
			(start 0.12065 0.3048)
			(end 0.67945 0.3048)
			(stroke
				(width 0.1)
				(type default)
			)
			(layer "B.Fab")
		)
		(fp_line
			(start 0.67945 0.3048)
			(end 0.67945 -0.305054)
			(stroke
				(width 0.1)
				(type default)
			)
			(layer "B.Fab")
		)
		(fp_line
			(start -0.120396 0.2794)
			(end 0.12065 0.2794)
			(stroke
				(width 0.1)
				(type default)
			)
			(layer "B.Fab")
		)
		(fp_line
			(start 0.12065 0.2794)
			(end 0.12065 0.3048)
			(stroke
				(width 0.1)
				(type default)
			)
			(layer "B.Fab")
		)
		(fp_line
			(start -0.12065 -0.2794)
			(end -0.12065 -0.3048)
			(stroke
				(width 0.1)
				(type default)
			)
			(layer "B.Fab")
		)
		(fp_line
			(start 0.12065 -0.2794)
			(end -0.12065 -0.2794)
			(stroke
				(width 0.1)
				(type default)
			)
			(layer "B.Fab")
		)
		(fp_line
			(start -0.67945 -0.3048)
			(end -0.67945 0.3048)
			(stroke
				(width 0.1)
				(type default)
			)
			(layer "B.Fab")
		)
		(fp_line
			(start -0.12065 -0.3048)
			(end -0.67945 -0.3048)
			(stroke
				(width 0.1)
				(type default)
			)
			(layer "B.Fab")
		)
		(fp_line
			(start 0.12065 -0.305054)
			(end 0.12065 -0.2794)
			(stroke
				(width 0.1)
				(type default)
			)
			(layer "B.Fab")
		)
		(fp_line
			(start 0.67945 -0.305054)
			(end 0.12065 -0.305054)
			(stroke
				(width 0.1)
				(type default)
			)
			(layer "B.Fab")
		)
		(pad "1" smd circle
			(at 0.40005 0 90)
			(size 0 0)
			(layers "B.Cu" "B.Mask" "B.Paste")
			(net "P12V_AUX")
		)
		(pad "2" smd circle
			(at -0.40005 0 90)
			(size 0 0)
			(layers "B.Cu" "B.Mask" "B.Paste")
			(net "VR_P5V_EN_D_R")
		)
	)
	(footprint ""
		(layer "B.Cu")
		(at 396.906242 -416.899344 90)
		(property "Reference" "C6614"
			(at 0 0 90)
			(layer "B.SilkS")
			(hide yes)
			(effects
				(font
					(size 1.27 1.27)
				)
				(justify mirror)
			)
		)
		(property "Value" ""
			(at 0 0 90)
			(layer "B.Fab")
			(effects
				(font
					(size 1.27 1.27)
				)
				(justify mirror)
			)
		)
		(duplicate_pad_numbers_are_jumpers no)
		(fp_line
			(start 0.299974 -0.150114)
			(end -0.299974 -0.150114)
			(stroke
				(width 0.1)
				(type default)
			)
			(layer "B.Fab")
		)
		(fp_line
			(start -0.299974 -0.150114)
			(end -0.299974 0.150114)
			(stroke
				(width 0.1)
				(type default)
			)
			(layer "B.Fab")
		)
		(fp_line
			(start 0.299974 0.150114)
			(end 0.299974 -0.150114)
			(stroke
				(width 0.1)
				(type default)
			)
			(layer "B.Fab")
		)
		(fp_line
			(start -0.299974 0.150114)
			(end 0.299974 0.150114)
			(stroke
				(width 0.1)
				(type default)
			)
			(layer "B.Fab")
		)
		(pad "1" smd rect
			(at 0.2667 0 270)
			(size 0.3048 0.381)
			(layers "B.Cu" "B.Mask" "B.Paste")
			(net "P5E_CPU0_P3_TX_BUF_C_DN<8>")
		)
		(pad "2" smd rect
			(at -0.2667 0 270)
			(size 0.3048 0.381)
			(layers "B.Cu" "B.Mask" "B.Paste")
			(net "P5E_CPU0_P3_TX_BUF_DN<8>")
		)
	)
	(footprint ""
		(layer "B.Cu")
		(at 56.99125 -390.560052 90)
		(property "Reference" "C119"
			(at 0 0 90)
			(layer "B.SilkS")
			(hide yes)
			(effects
				(font
					(size 1.27 1.27)
				)
				(justify mirror)
			)
		)
		(property "Value" ""
			(at 0 0 90)
			(layer "B.Fab")
			(effects
				(font
					(size 1.27 1.27)
				)
				(justify mirror)
			)
		)
		(duplicate_pad_numbers_are_jumpers no)
		(fp_line
			(start 0.7874 -0.4064)
			(end -0.7874 -0.4064)
			(stroke
				(width 0.1524)
				(type default)
			)
			(layer "B.SilkS")
		)
		(fp_line
			(start -0.7874 -0.4064)
			(end -0.7874 0.4064)
			(stroke
				(width 0.1524)
				(type default)
			)
			(layer "B.SilkS")
		)
		(fp_line
			(start 0.7874 0.4064)
			(end 0.7874 -0.4064)
			(stroke
				(width 0.1524)
				(type default)
			)
			(layer "B.SilkS")
		)
		(fp_line
			(start -0.7874 0.4064)
			(end 0.7874 0.4064)
			(stroke
				(width 0.1524)
				(type default)
			)
			(layer "B.SilkS")
		)
		(fp_line
			(start 0.67945 -0.305054)
			(end 0.12065 -0.305054)
			(stroke
				(width 0.1)
				(type default)
			)
			(layer "B.Fab")
		)
		(fp_line
			(start 0.12065 -0.305054)
			(end 0.12065 -0.2794)
			(stroke
				(width 0.1)
				(type default)
			)
			(layer "B.Fab")
		)
		(fp_line
			(start -0.12065 -0.3048)
			(end -0.67945 -0.3048)
			(stroke
				(width 0.1)
				(type default)
			)
			(layer "B.Fab")
		)
		(fp_line
			(start -0.67945 -0.3048)
			(end -0.67945 0.3048)
			(stroke
				(width 0.1)
				(type default)
			)
			(layer "B.Fab")
		)
		(fp_line
			(start 0.12065 -0.2794)
			(end -0.12065 -0.2794)
			(stroke
				(width 0.1)
				(type default)
			)
			(layer "B.Fab")
		)
		(fp_line
			(start -0.12065 -0.2794)
			(end -0.12065 -0.3048)
			(stroke
				(width 0.1)
				(type default)
			)
			(layer "B.Fab")
		)
		(fp_line
			(start 0.12065 0.2794)
			(end 0.12065 0.3048)
			(stroke
				(width 0.1)
				(type default)
			)
			(layer "B.Fab")
		)
		(fp_line
			(start -0.120396 0.2794)
			(end 0.12065 0.2794)
			(stroke
				(width 0.1)
				(type default)
			)
			(layer "B.Fab")
		)
		(fp_line
			(start 0.67945 0.3048)
			(end 0.67945 -0.305054)
			(stroke
				(width 0.1)
				(type default)
			)
			(layer "B.Fab")
		)
		(fp_line
			(start 0.12065 0.3048)
			(end 0.67945 0.3048)
			(stroke
				(width 0.1)
				(type default)
			)
			(layer "B.Fab")
		)
		(fp_line
			(start -0.120396 0.3048)
			(end -0.120396 0.2794)
			(stroke
				(width 0.1)
				(type default)
			)
			(layer "B.Fab")
		)
		(fp_line
			(start -0.67945 0.3048)
			(end -0.120396 0.3048)
			(stroke
				(width 0.1)
				(type default)
			)
			(layer "B.Fab")
		)
		(pad "1" smd circle
			(at 0.40005 0 270)
			(size 0 0)
			(layers "B.Cu" "B.Mask" "B.Paste")
			(net "P1V8_CPU1_RT0_1A")
		)
		(pad "2" smd circle
			(at -0.40005 0 270)
			(size 0 0)
			(layers "B.Cu" "B.Mask" "B.Paste")
			(net "GND")
		)
	)
)
